(kicad_pcb
	(version 20241229)
	(generator "pcbnew")
	(generator_version "9.0")
	(general
		(thickness 1.599998)
		(legacy_teardrops no)
	)
	(paper "A4")
	(title_block
		(title "Artix - Datacenter Secure Control Module (DC-SCM)")
		(date "2024-11-06")
		(rev "1.1.3")
		(comment 9 "footprints 145-149 of 544")
	)
	(layers
		(0 "F.Cu" signal)
		(4 "In1.Cu" signal)
		(6 "In2.Cu" signal)
		(8 "In3.Cu" signal)
		(10 "In4.Cu" signal)
		(12 "In5.Cu" signal)
		(14 "In6.Cu" signal)
		(2 "B.Cu" signal)
		(9 "F.Adhes" user "F.Adhesive")
		(11 "B.Adhes" user "B.Adhesive")
		(13 "F.Paste" user)
		(15 "B.Paste" user)
		(5 "F.SilkS" user "F.Silkscreen")
		(7 "B.SilkS" user "B.Silkscreen")
		(1 "F.Mask" user)
		(3 "B.Mask" user)
		(17 "Dwgs.User" user "User.Drawings")
		(19 "Cmts.User" user "User.Comments")
		(21 "Eco1.User" user "User.Eco1")
		(23 "Eco2.User" user "User.Eco2")
		(25 "Edge.Cuts" user)
		(27 "Margin" user)
		(31 "F.CrtYd" user "F.Courtyard")
		(29 "B.CrtYd" user "B.Courtyard")
		(35 "F.Fab" user)
		(33 "B.Fab" user)
	)
	(footprint "antmicro-footprints:L_Vishay-IHLP-1212AE"
		(layer "F.Cu")
		(at 82.65 87.2 90)
		(property "Reference" "L5"
			(at -2.067 -0.6545 90)
			(layer "F.SilkS")
			(effects
				(font
					(size 0.7 0.7)
					(thickness 0.15)
				)
				(justify left bottom)
			)
		)
		(property "Value" "L_470n_6.7A_Vishay-IHLP-1212AE-11"
			(at 1.278 3.401 90)
			(layer "F.Fab")
			(effects
				(font
					(size 0.7 0.7)
					(thickness 0.15)
				)
				(justify left bottom)
			)
		)
		(property "Datasheet" "https://www.vishay.com/docs/34300/ihlp-1212ae-11.pdf"
			(at 0 0 90)
			(layer "F.Fab")
			(hide yes)
			(effects
				(font
					(size 1.27 1.27)
					(thickness 0.15)
				)
			)
		)
		(property "Description" "Power Inductor (SMT), 470 nH, 6.7 A, Shielded, 6.7 A"
			(at 0 0 90)
			(layer "F.Fab")
			(hide yes)
			(effects
				(font
					(size 1.27 1.27)
					(thickness 0.15)
				)
			)
		)
		(property "Author" "Antmicro"
			(at 169.85 4.55 0)
			(layer "F.Fab")
			(hide yes)
			(effects
				(font
					(size 1 1)
					(thickness 0.15)
				)
			)
		)
		(property "IMax" "6.7 A"
			(at 169.85 4.55 0)
			(layer "F.Fab")
			(hide yes)
			(effects
				(font
					(size 1 1)
					(thickness 0.15)
				)
			)
		)
		(property "ISat" "6.7 A"
			(at 169.85 4.55 0)
			(layer "F.Fab")
			(hide yes)
			(effects
				(font
					(size 1 1)
					(thickness 0.15)
				)
			)
		)
		(property "License" "Apache-2.0"
			(at 169.85 4.55 0)
			(layer "F.Fab")
			(hide yes)
			(effects
				(font
					(size 1 1)
					(thickness 0.15)
				)
			)
		)
		(property "MPN" "IHLP1212AEERR47M11"
			(at 169.85 4.55 0)
			(layer "F.Fab")
			(hide yes)
			(effects
				(font
					(size 1 1)
					(thickness 0.15)
				)
			)
		)
		(property "Manufacturer" "Vishay"
			(at 169.85 4.55 0)
			(layer "F.Fab")
			(hide yes)
			(effects
				(font
					(size 1 1)
					(thickness 0.15)
				)
			)
		)
		(property "Size" "3.0x3.0"
			(at 169.85 4.55 0)
			(layer "F.Fab")
			(hide yes)
			(effects
				(font
					(size 1 1)
					(thickness 0.15)
				)
			)
		)
		(property "Val" "470n/6.7A"
			(at 169.85 4.55 0)
			(layer "F.Fab")
			(hide yes)
			(effects
				(font
					(size 1 1)
					(thickness 0.15)
				)
			)
		)
		(sheetname "/Power supply/")
		(sheetfile "power-supply.kicad_sch")
		(attr smd)
		(fp_line
			(start 1.653 -1.6)
			(end 1.653 -0.9)
			(stroke
				(width 0.15)
				(type solid)
			)
			(layer "F.SilkS")
		)
		(fp_line
			(start -1.647 -1.6)
			(end 1.653 -1.6)
			(stroke
				(width 0.15)
				(type solid)
			)
			(layer "F.SilkS")
		)
		(fp_line
			(start -1.647 -0.9)
			(end -1.647 -1.6)
			(stroke
				(width 0.15)
				(type solid)
			)
			(layer "F.SilkS")
		)
		(fp_line
			(start 1.653 0.9)
			(end 1.653 1.601)
			(stroke
				(width 0.15)
				(type solid)
			)
			(layer "F.SilkS")
		)
		(fp_line
			(start -1.647 1.6)
			(end -1.647 0.9)
			(stroke
				(width 0.15)
				(type solid)
			)
			(layer "F.SilkS")
		)
		(fp_line
			(start 1.653 1.601)
			(end -1.647 1.6)
			(stroke
				(width 0.15)
				(type solid)
			)
			(layer "F.SilkS")
		)
		(fp_rect
			(start -2.35 -1.85)
			(end 2.35 1.85)
			(stroke
				(width 0.05)
				(type solid)
			)
			(fill no)
			(layer "F.CrtYd")
		)
		(fp_rect
			(start -1.803 -1.601)
			(end 1.803 1.601)
			(stroke
				(width 0.15)
				(type solid)
			)
			(fill no)
			(layer "F.Fab")
		)
		(pad "1" smd roundrect
			(at -1.35 0 90)
			(size 1.5 1.2)
			(layers "F.Cu" "F.Mask" "F.Paste")
			(roundrect_rratio 0.1)
			(net 290 "Net-(U13-SW)")
			(pintype "passive")
		)
		(pad "2" smd roundrect
			(at 1.35 0 90)
			(size 1.5 1.2)
			(layers "F.Cu" "F.Mask" "F.Paste")
			(roundrect_rratio 0.1)
			(net 277 "Net-(C82-Pad2)")
			(pintype "passive")
		)
	)
	(footprint "antmicro-footprints:R_0603_1608Metric"
		(layer "F.Cu")
		(at 80.15 100.175 -90)
		(descr "Resistor SMD 0603")
		(tags "resistor SMD 0603")
		(property "Reference" "R139"
			(at 1.025 -0.325 90)
			(layer "F.SilkS")
			(effects
				(font
					(size 0.7 0.7)
					(thickness 0.15)
				)
				(justify right bottom)
			)
		)
		(property "Value" "R_0R_0603"
			(at 0 1.6 90)
			(layer "F.Fab")
			(effects
				(font
					(size 0.7 0.7)
					(thickness 0.15)
				)
				(justify right bottom)
			)
		)
		(property "Datasheet" "https://www.bourns.com/docs/product-datasheets/cr.pdf?sfvrsn=574d41f6_14"
			(at 0 0 270)
			(layer "F.Fab")
			(hide yes)
			(effects
				(font
					(size 1.27 1.27)
					(thickness 0.15)
				)
			)
		)
		(property "Description" "Zero Ohm Resistor, Jumper, 0603 [1608 Metric], Thick Film, 100 mW, 1 A, Surface Mount Device, CR"
			(at 0 0 270)
			(layer "F.Fab")
			(hide yes)
			(effects
				(font
					(size 1.27 1.27)
					(thickness 0.15)
				)
			)
		)
		(property "Author" "Antmicro"
			(at -20.025 180.325 0)
			(layer "F.Fab")
			(hide yes)
			(effects
				(font
					(size 1 1)
					(thickness 0.15)
				)
			)
		)
		(property "Current" "1A"
			(at -20.025 180.325 0)
			(layer "F.Fab")
			(hide yes)
			(effects
				(font
					(size 1 1)
					(thickness 0.15)
				)
			)
		)
		(property "License" "Apache-2.0"
			(at -20.025 180.325 0)
			(layer "F.Fab")
			(hide yes)
			(effects
				(font
					(size 1 1)
					(thickness 0.15)
				)
			)
		)
		(property "MPN" "CR0603-J/-000ELF"
			(at -20.025 180.325 0)
			(layer "F.Fab")
			(hide yes)
			(effects
				(font
					(size 1 1)
					(thickness 0.15)
				)
			)
		)
		(property "Manufacturer" "Bourns"
			(at -20.025 180.325 0)
			(layer "F.Fab")
			(hide yes)
			(effects
				(font
					(size 1 1)
					(thickness 0.15)
				)
			)
		)
		(property "Tolerance" "~"
			(at -20.025 180.325 0)
			(layer "F.Fab")
			(hide yes)
			(effects
				(font
					(size 1 1)
					(thickness 0.15)
				)
			)
		)
		(property "Val" "0R"
			(at -20.025 180.325 0)
			(layer "F.Fab")
			(hide yes)
			(effects
				(font
					(size 1 1)
					(thickness 0.15)
				)
			)
		)
		(sheetname "/Power supply/")
		(sheetfile "power-supply.kicad_sch")
		(attr smd)
		(fp_line
			(start -0.15 0.4)
			(end 0.15 0.4)
			(stroke
				(width 0.15)
				(type solid)
			)
			(layer "F.SilkS")
		)
		(fp_line
			(start -0.15 -0.4)
			(end 0.15 -0.4)
			(stroke
				(width 0.15)
				(type solid)
			)
			(layer "F.SilkS")
		)
		(fp_rect
			(start -1.25 -0.65)
			(end 1.25 0.65)
			(stroke
				(width 0.05)
				(type solid)
			)
			(fill no)
			(layer "F.CrtYd")
		)
		(fp_rect
			(start -0.8 -0.4)
			(end 0.8 0.4)
			(stroke
				(width 0.15)
				(type solid)
			)
			(fill no)
			(layer "F.Fab")
		)
		(pad "1" smd roundrect
			(at -0.7 0 270)
			(size 0.8 1)
			(layers "F.Cu" "F.Mask" "F.Paste")
			(roundrect_rratio 0.2)
			(net 2 "VCC3V3")
			(pintype "passive")
		)
		(pad "2" smd roundrect
			(at 0.7 0 270)
			(size 0.8 1)
			(layers "F.Cu" "F.Mask" "F.Paste")
			(roundrect_rratio 0.2)
			(net 274 "Net-(C79-Pad2)")
			(pintype "passive")
		)
	)
	(footprint "antmicro-footprints:R_0603_1608Metric"
		(layer "F.Cu")
		(at 79.925 79.4 90)
		(descr "Resistor SMD 0603")
		(tags "resistor SMD 0603")
		(property "Reference" "R141"
			(at -3.9 0.175 90)
			(layer "F.SilkS")
			(effects
				(font
					(size 0.7 0.7)
					(thickness 0.15)
				)
				(justify left bottom)
			)
		)
		(property "Value" "R_0R_0603"
			(at 0 1.6 90)
			(layer "F.Fab")
			(effects
				(font
					(size 0.7 0.7)
					(thickness 0.15)
				)
				(justify left bottom)
			)
		)
		(property "Datasheet" "https://www.bourns.com/docs/product-datasheets/cr.pdf?sfvrsn=574d41f6_14"
			(at 0 0 90)
			(layer "F.Fab")
			(hide yes)
			(effects
				(font
					(size 1.27 1.27)
					(thickness 0.15)
				)
			)
		)
		(property "Description" "Zero Ohm Resistor, Jumper, 0603 [1608 Metric], Thick Film, 100 mW, 1 A, Surface Mount Device, CR"
			(at 0 0 90)
			(layer "F.Fab")
			(hide yes)
			(effects
				(font
					(size 1.27 1.27)
					(thickness 0.15)
				)
			)
		)
		(property "Author" "Antmicro"
			(at 159.325 -0.525 0)
			(layer "F.Fab")
			(hide yes)
			(effects
				(font
					(size 1 1)
					(thickness 0.15)
				)
			)
		)
		(property "Current" "1A"
			(at 159.325 -0.525 0)
			(layer "F.Fab")
			(hide yes)
			(effects
				(font
					(size 1 1)
					(thickness 0.15)
				)
			)
		)
		(property "License" "Apache-2.0"
			(at 159.325 -0.525 0)
			(layer "F.Fab")
			(hide yes)
			(effects
				(font
					(size 1 1)
					(thickness 0.15)
				)
			)
		)
		(property "MPN" "CR0603-J/-000ELF"
			(at 159.325 -0.525 0)
			(layer "F.Fab")
			(hide yes)
			(effects
				(font
					(size 1 1)
					(thickness 0.15)
				)
			)
		)
		(property "Manufacturer" "Bourns"
			(at 159.325 -0.525 0)
			(layer "F.Fab")
			(hide yes)
			(effects
				(font
					(size 1 1)
					(thickness 0.15)
				)
			)
		)
		(property "Tolerance" "~"
			(at 159.325 -0.525 0)
			(layer "F.Fab")
			(hide yes)
			(effects
				(font
					(size 1 1)
					(thickness 0.15)
				)
			)
		)
		(property "Val" "0R"
			(at 159.325 -0.525 0)
			(layer "F.Fab")
			(hide yes)
			(effects
				(font
					(size 1 1)
					(thickness 0.15)
				)
			)
		)
		(sheetname "/Power supply/")
		(sheetfile "power-supply.kicad_sch")
		(attr smd)
		(fp_line
			(start -0.15 -0.4)
			(end 0.15 -0.4)
			(stroke
				(width 0.15)
				(type solid)
			)
			(layer "F.SilkS")
		)
		(fp_line
			(start -0.15 0.4)
			(end 0.15 0.4)
			(stroke
				(width 0.15)
				(type solid)
			)
			(layer "F.SilkS")
		)
		(fp_rect
			(start -1.25 -0.65)
			(end 1.25 0.65)
			(stroke
				(width 0.05)
				(type solid)
			)
			(fill no)
			(layer "F.CrtYd")
		)
		(fp_rect
			(start -0.8 -0.4)
			(end 0.8 0.4)
			(stroke
				(width 0.15)
				(type solid)
			)
			(fill no)
			(layer "F.Fab")
		)
		(pad "1" smd roundrect
			(at -0.7 0 90)
			(size 0.8 1)
			(layers "F.Cu" "F.Mask" "F.Paste")
			(roundrect_rratio 0.2)
			(net 6 "VCC1V0")
			(pintype "passive")
		)
		(pad "2" smd roundrect
			(at 0.7 0 90)
			(size 0.8 1)
			(layers "F.Cu" "F.Mask" "F.Paste")
			(roundrect_rratio 0.2)
			(net 276 "Net-(C81-Pad2)")
			(pintype "passive")
		)
	)
	(footprint "antmicro-footprints:R_0603_1608Metric"
		(layer "F.Cu")
		(at 79.775 85.375 -90)
		(descr "Resistor SMD 0603")
		(tags "resistor SMD 0603")
		(property "Reference" "R142"
			(at 1.025 -0.325 90)
			(layer "F.SilkS")
			(effects
				(font
					(size 0.7 0.7)
					(thickness 0.15)
				)
				(justify right bottom)
			)
		)
		(property "Value" "R_0R_0603"
			(at 0 1.6 90)
			(layer "F.Fab")
			(effects
				(font
					(size 0.7 0.7)
					(thickness 0.15)
				)
				(justify right bottom)
			)
		)
		(property "Datasheet" "https://www.bourns.com/docs/product-datasheets/cr.pdf?sfvrsn=574d41f6_14"
			(at 0 0 270)
			(layer "F.Fab")
			(hide yes)
			(effects
				(font
					(size 1.27 1.27)
					(thickness 0.15)
				)
			)
		)
		(property "Description" "Zero Ohm Resistor, Jumper, 0603 [1608 Metric], Thick Film, 100 mW, 1 A, Surface Mount Device, CR"
			(at 0 0 270)
			(layer "F.Fab")
			(hide yes)
			(effects
				(font
					(size 1.27 1.27)
					(thickness 0.15)
				)
			)
		)
		(property "Author" "Antmicro"
			(at -5.6 165.15 0)
			(layer "F.Fab")
			(hide yes)
			(effects
				(font
					(size 1 1)
					(thickness 0.15)
				)
			)
		)
		(property "Current" "1A"
			(at -5.6 165.15 0)
			(layer "F.Fab")
			(hide yes)
			(effects
				(font
					(size 1 1)
					(thickness 0.15)
				)
			)
		)
		(property "License" "Apache-2.0"
			(at -5.6 165.15 0)
			(layer "F.Fab")
			(hide yes)
			(effects
				(font
					(size 1 1)
					(thickness 0.15)
				)
			)
		)
		(property "MPN" "CR0603-J/-000ELF"
			(at -5.6 165.15 0)
			(layer "F.Fab")
			(hide yes)
			(effects
				(font
					(size 1 1)
					(thickness 0.15)
				)
			)
		)
		(property "Manufacturer" "Bourns"
			(at -5.6 165.15 0)
			(layer "F.Fab")
			(hide yes)
			(effects
				(font
					(size 1 1)
					(thickness 0.15)
				)
			)
		)
		(property "Tolerance" "~"
			(at -5.6 165.15 0)
			(layer "F.Fab")
			(hide yes)
			(effects
				(font
					(size 1 1)
					(thickness 0.15)
				)
			)
		)
		(property "Val" "0R"
			(at -5.6 165.15 0)
			(layer "F.Fab")
			(hide yes)
			(effects
				(font
					(size 1 1)
					(thickness 0.15)
				)
			)
		)
		(sheetname "/Power supply/")
		(sheetfile "power-supply.kicad_sch")
		(attr smd)
		(fp_line
			(start -0.15 0.4)
			(end 0.15 0.4)
			(stroke
				(width 0.15)
				(type solid)
			)
			(layer "F.SilkS")
		)
		(fp_line
			(start -0.15 -0.4)
			(end 0.15 -0.4)
			(stroke
				(width 0.15)
				(type solid)
			)
			(layer "F.SilkS")
		)
		(fp_rect
			(start -1.25 -0.65)
			(end 1.25 0.65)
			(stroke
				(width 0.05)
				(type solid)
			)
			(fill no)
			(layer "F.CrtYd")
		)
		(fp_rect
			(start -0.8 -0.4)
			(end 0.8 0.4)
			(stroke
				(width 0.15)
				(type solid)
			)
			(fill no)
			(layer "F.Fab")
		)
		(pad "1" smd roundrect
			(at -0.7 0 270)
			(size 0.8 1)
			(layers "F.Cu" "F.Mask" "F.Paste")
			(roundrect_rratio 0.2)
			(net 3 "VCC1V35")
			(pintype "passive")
		)
		(pad "2" smd roundrect
			(at 0.7 0 270)
			(size 0.8 1)
			(layers "F.Cu" "F.Mask" "F.Paste")
			(roundrect_rratio 0.2)
			(net 277 "Net-(C82-Pad2)")
			(pintype "passive")
		)
	)
	(footprint "antmicro-footprints:R_0603_1608Metric"
		(layer "F.Cu")
		(at 79.675 92.575 -90)
		(descr "Resistor SMD 0603")
		(tags "resistor SMD 0603")
		(property "Reference" "R140"
			(at 1.025 -0.325 90)
			(layer "F.SilkS")
			(effects
				(font
					(size 0.7 0.7)
					(thickness 0.15)
				)
				(justify right bottom)
			)
		)
		(property "Value" "R_0R_0603"
			(at 0 1.6 90)
			(layer "F.Fab")
			(effects
				(font
					(size 0.7 0.7)
					(thickness 0.15)
				)
				(justify right bottom)
			)
		)
		(property "Datasheet" "https://www.bourns.com/docs/product-datasheets/cr.pdf?sfvrsn=574d41f6_14"
			(at 0 0 270)
			(layer "F.Fab")
			(hide yes)
			(effects
				(font
					(size 1.27 1.27)
					(thickness 0.15)
				)
			)
		)
		(property "Description" "Zero Ohm Resistor, Jumper, 0603 [1608 Metric], Thick Film, 100 mW, 1 A, Surface Mount Device, CR"
			(at 0 0 270)
			(layer "F.Fab")
			(hide yes)
			(effects
				(font
					(size 1.27 1.27)
					(thickness 0.15)
				)
			)
		)
		(property "Author" "Antmicro"
			(at -12.9 172.25 0)
			(layer "F.Fab")
			(hide yes)
			(effects
				(font
					(size 1 1)
					(thickness 0.15)
				)
			)
		)
		(property "Current" "1A"
			(at -12.9 172.25 0)
			(layer "F.Fab")
			(hide yes)
			(effects
				(font
					(size 1 1)
					(thickness 0.15)
				)
			)
		)
		(property "License" "Apache-2.0"
			(at -12.9 172.25 0)
			(layer "F.Fab")
			(hide yes)
			(effects
				(font
					(size 1 1)
					(thickness 0.15)
				)
			)
		)
		(property "MPN" "CR0603-J/-000ELF"
			(at -12.9 172.25 0)
			(layer "F.Fab")
			(hide yes)
			(effects
				(font
					(size 1 1)
					(thickness 0.15)
				)
			)
		)
		(property "Manufacturer" "Bourns"
			(at -12.9 172.25 0)
			(layer "F.Fab")
			(hide yes)
			(effects
				(font
					(size 1 1)
					(thickness 0.15)
				)
			)
		)
		(property "Tolerance" "~"
			(at -12.9 172.25 0)
			(layer "F.Fab")
			(hide yes)
			(effects
				(font
					(size 1 1)
					(thickness 0.15)
				)
			)
		)
		(property "Val" "0R"
			(at -12.9 172.25 0)
			(layer "F.Fab")
			(hide yes)
			(effects
				(font
					(size 1 1)
					(thickness 0.15)
				)
			)
		)
		(sheetname "/Power supply/")
		(sheetfile "power-supply.kicad_sch")
		(attr smd)
		(fp_line
			(start -0.15 0.4)
			(end 0.15 0.4)
			(stroke
				(width 0.15)
				(type solid)
			)
			(layer "F.SilkS")
		)
		(fp_line
			(start -0.15 -0.4)
			(end 0.15 -0.4)
			(stroke
				(width 0.15)
				(type solid)
			)
			(layer "F.SilkS")
		)
		(fp_rect
			(start -1.25 -0.65)
			(end 1.25 0.65)
			(stroke
				(width 0.05)
				(type solid)
			)
			(fill no)
			(layer "F.CrtYd")
		)
		(fp_rect
			(start -0.8 -0.4)
			(end 0.8 0.4)
			(stroke
				(width 0.15)
				(type solid)
			)
			(fill no)
			(layer "F.Fab")
		)
		(pad "1" smd roundrect
			(at -0.7 0 270)
			(size 0.8 1)
			(layers "F.Cu" "F.Mask" "F.Paste")
			(roundrect_rratio 0.2)
			(net 5 "VCC1V8")
			(pintype "passive")
		)
		(pad "2" smd roundrect
			(at 0.7 0 270)
			(size 0.8 1)
			(layers "F.Cu" "F.Mask" "F.Paste")
			(roundrect_rratio 0.2)
			(net 275 "Net-(C80-Pad2)")
			(pintype "passive")
		)
	)
)
